(kicad_pcb
	(version 20260206)
	(generator "pcbnew")
	(generator_version "10.0")
	(general
		(thickness 1.6)
		(legacy_teardrops no)
	)
	(paper "A4")
	(title_block
		(title "v1-tray-backplane — T6M_tray_BP_c_1023_1120.brd")
		(comment 1 "Open CloudServer (Microsoft) / footprints 98-100 of 170")
	)
	(layers
		(0 "F.Cu" signal "TOP")
		(4 "In1.Cu" signal "GND")
		(6 "In2.Cu" signal "IN1")
		(8 "In3.Cu" signal "VCC")
		(10 "In4.Cu" signal "VCC1")
		(12 "In5.Cu" signal "IN2")
		(14 "In6.Cu" signal "GND1")
		(2 "B.Cu" signal "BOTTOM")
		(9 "F.Adhes" user "F.Adhesive")
		(11 "B.Adhes" user "B.Adhesive")
		(13 "F.Paste" user "Package Geometry/Pastemask Top")
		(15 "B.Paste" user "Package Geometry/Pastemask Bottom")
		(5 "F.SilkS" user "Ref Des/Silkscreen Top")
		(7 "B.SilkS" user "Ref Des/Silkscreen Bottom")
		(1 "F.Mask" user "Board Geometry/Soldermask Top")
		(3 "B.Mask" user "Board Geometry/Soldermask Bottom")
		(17 "Dwgs.User" user "User.Drawings")
		(19 "Cmts.User" user "User.Comments")
		(21 "Eco1.User" user "User.Eco1")
		(23 "Eco2.User" user "User.Eco2")
		(25 "Edge.Cuts" user "Board Geometry/Outline")
		(27 "Margin" user)
		(31 "F.CrtYd" user "Package Geometry/Place Bound Top")
		(29 "B.CrtYd" user "Package Geometry/Place Bound Bottom")
		(35 "F.Fab" user "Ref Des/Assembly Top")
		(33 "B.Fab" user "Ref Des/Assembly Bottom")
	)
	(footprint ""
		(layer "F.Cu")
		(at 92.140786 -23.442676 -90)
		(property "Reference" "C4"
			(at -0.561848 5.50672 90)
			(unlocked yes)
			(layer "F.SilkS")
			(effects
				(font
					(size 0.7874 0.5842)
					(thickness 0.1524)
				)
				(justify left)
			)
		)
		(property "Value" ""
			(at 0 0 270)
			(layer "F.Fab")
			(effects
				(font
					(size 1.27 1.27)
				)
			)
		)
		(duplicate_pad_numbers_are_jumpers no)
		(fp_line
			(start -0.7874 0.4064)
			(end -0.7874 -0.4064)
			(stroke
				(width 0.1524)
				(type default)
			)
			(layer "F.SilkS")
		)
		(fp_line
			(start 0.7874 0.4064)
			(end -0.7874 0.4064)
			(stroke
				(width 0.1524)
				(type default)
			)
			(layer "F.SilkS")
		)
		(fp_line
			(start 0 0.381)
			(end 0 -0.381)
			(stroke
				(width 0.1524)
				(type default)
			)
			(layer "F.SilkS")
		)
		(fp_line
			(start -0.7874 -0.4064)
			(end 0.7874 -0.4064)
			(stroke
				(width 0.1524)
				(type default)
			)
			(layer "F.SilkS")
		)
		(fp_line
			(start 0.7874 -0.4064)
			(end 0.7874 0.4064)
			(stroke
				(width 0.1524)
				(type default)
			)
			(layer "F.SilkS")
		)
		(fp_poly
			(pts
				(xy -0.5334 0.254) (xy -0.635 0.254) (xy -0.635 0.2286) (xy -0.635 -0.254) (xy -0.5334 -0.254) (xy -0.5334 -0.2794)
				(xy 0.5334 -0.2794) (xy 0.5334 -0.254) (xy 0.635 -0.254) (xy 0.635 0.254) (xy 0.5334 0.254) (xy 0.5334 0.2794)
				(xy -0.508 0.2794) (xy -0.5334 0.2794)
			)
			(stroke
				(width 0)
				(type default)
			)
			(fill no)
			(layer "F.CrtYd")
		)
		(pad "1" smd rect
			(at 0.40005 0 270)
			(size 0.4572 0.508)
			(layers "F.Cu" "F.Mask" "F.Paste")
			(net "P12V")
		)
		(pad "2" smd rect
			(at -0.40005 0 270)
			(size 0.4572 0.508)
			(layers "F.Cu" "F.Mask" "F.Paste")
			(net "GND")
		)
	)
	(footprint ""
		(layer "F.Cu")
		(at 156.0576 -30.545532 180)
		(property "Reference" "R77"
			(at -33.9598 -19.690334 0)
			(unlocked yes)
			(layer "F.SilkS")
			(effects
				(font
					(size 0.7874 0.5842)
					(thickness 0.1524)
				)
				(justify left)
			)
		)
		(property "Value" ""
			(at 0 0 180)
			(layer "F.Fab")
			(effects
				(font
					(size 1.27 1.27)
				)
			)
		)
		(duplicate_pad_numbers_are_jumpers no)
		(fp_line
			(start 1.905 0.8636)
			(end -1.905 0.8636)
			(stroke
				(width 0.1524)
				(type default)
			)
			(layer "F.SilkS")
		)
		(fp_line
			(start 1.905 -0.8636)
			(end 1.905 0.8636)
			(stroke
				(width 0.1524)
				(type default)
			)
			(layer "F.SilkS")
		)
		(fp_line
			(start -1.905 0.8636)
			(end -1.905 -0.8636)
			(stroke
				(width 0.1524)
				(type default)
			)
			(layer "F.SilkS")
		)
		(fp_line
			(start -1.905 -0.8636)
			(end 1.905 -0.8636)
			(stroke
				(width 0.1524)
				(type default)
			)
			(layer "F.SilkS")
		)
		(fp_poly
			(pts
				(xy 1.524 0.6858) (xy 1.524 -0.6858) (xy 1.524 -0.7366) (xy -1.524 -0.7366) (xy -1.524 -0.6858)
				(xy -1.524 0.6858) (xy -1.524 0.7366) (xy 1.524 0.7366)
			)
			(stroke
				(width 0)
				(type default)
			)
			(fill no)
			(layer "F.CrtYd")
		)
		(pad "1" smd rect
			(at 0.94996 0 180)
			(size 1.1176 1.3716)
			(layers "F.Cu" "F.Mask" "F.Paste")
			(net "P3V3_BLAD1")
		)
		(pad "2" smd rect
			(at -0.94996 0 180)
			(size 1.1176 1.3716)
			(layers "F.Cu" "F.Mask" "F.Paste")
			(net "P3V3_10G_1_VCCR")
		)
	)
	(footprint ""
		(layer "F.Cu")
		(at 338.153248 -25.206706)
		(property "Reference" "R30"
			(at -58.3692 -4.435348 0)
			(unlocked yes)
			(layer "F.SilkS")
			(effects
				(font
					(size 0.7874 0.5842)
					(thickness 0.1524)
				)
				(justify left)
			)
		)
		(property "Value" ""
			(at 0 0 0)
			(layer "F.Fab")
			(effects
				(font
					(size 1.27 1.27)
				)
			)
		)
		(duplicate_pad_numbers_are_jumpers no)
		(fp_line
			(start -0.7874 -0.4064)
			(end 0.7874 -0.4064)
			(stroke
				(width 0.1524)
				(type default)
			)
			(layer "F.SilkS")
		)
		(fp_line
			(start -0.7874 0.4064)
			(end -0.7874 -0.4064)
			(stroke
				(width 0.1524)
				(type default)
			)
			(layer "F.SilkS")
		)
		(fp_line
			(start 0.7874 -0.4064)
			(end 0.7874 0.4064)
			(stroke
				(width 0.1524)
				(type default)
			)
			(layer "F.SilkS")
		)
		(fp_line
			(start 0.7874 0.4064)
			(end -0.7874 0.4064)
			(stroke
				(width 0.1524)
				(type default)
			)
			(layer "F.SilkS")
		)
		(fp_poly
			(pts
				(xy -0.508 0.2794) (xy -0.508 0.2286) (xy -0.635 0.2286) (xy -0.635 -0.254) (xy -0.5334 -0.254)
				(xy -0.5334 -0.2794) (xy 0.5334 -0.2794) (xy 0.5334 -0.254) (xy 0.635 -0.254) (xy 0.635 0.254) (xy 0.5334 0.254)
				(xy 0.5334 0.2794)
			)
			(stroke
				(width 0)
				(type default)
			)
			(fill no)
			(layer "F.CrtYd")
		)
		(pad "1" smd rect
			(at 0.40005 0)
			(size 0.4572 0.508)
			(layers "F.Cu" "F.Mask" "F.Paste")
			(net "P3V3_BLAD2")
		)
		(pad "2" smd rect
			(at -0.40005 0)
			(size 0.4572 0.508)
			(layers "F.Cu" "F.Mask" "F.Paste")
			(net "ENET10G_4_LOS")
		)
	)
)
